(kicad_pcb
	(version 20260206)
	(generator "pcbnew")
	(generator_version "10.0")
	(general
		(thickness 1.6)
		(legacy_teardrops no)
	)
	(paper "A4")
	(title_block
		(title "Wiwynn_Tioga_Pass_MB.brd")
		(comment 1 "Tioga Pass / footprints 4425-4431 of 4770")
	)
	(layers
		(0 "F.Cu" signal "TOP")
		(4 "In1.Cu" signal "L2GND")
		(6 "In2.Cu" signal "L3")
		(8 "In3.Cu" signal "L4GND")
		(10 "In4.Cu" signal "L5")
		(12 "In5.Cu" signal "L6GND")
		(14 "In6.Cu" signal "L7VCC")
		(16 "In7.Cu" signal "L8VCC")
		(18 "In8.Cu" signal "L9GND")
		(20 "In9.Cu" signal "L10")
		(22 "In10.Cu" signal "L11GND")
		(24 "In11.Cu" signal "L12")
		(26 "In12.Cu" signal "L13GND")
		(2 "B.Cu" signal "BOTTOM")
		(9 "F.Adhes" user "F.Adhesive")
		(11 "B.Adhes" user "B.Adhesive")
		(13 "F.Paste" user "Package Geometry/Pastemask Top")
		(15 "B.Paste" user "Package Geometry/Pastemask Bottom")
		(5 "F.SilkS" user "Ref Des/Silkscreen Top")
		(7 "B.SilkS" user "Ref Des/Silkscreen Bottom")
		(1 "F.Mask" user "Board Geometry/Soldermask Top")
		(3 "B.Mask" user "Board Geometry/Soldermask Bottom")
		(17 "Dwgs.User" user "User.Drawings")
		(19 "Cmts.User" user "User.Comments")
		(21 "Eco1.User" user "User.Eco1")
		(23 "Eco2.User" user "User.Eco2")
		(25 "Edge.Cuts" user "Board Geometry/Outline")
		(27 "Margin" user)
		(31 "F.CrtYd" user "Package Geometry/Place Bound Top")
		(29 "B.CrtYd" user "Package Geometry/Place Bound Bottom")
		(35 "F.Fab" user "Ref Des/Assembly Top")
		(33 "B.Fab" user "Ref Des/Assembly Bottom")
	)
	(footprint ""
		(layer "B.Cu")
		(at 470.027 -62.484 -90)
		(property "Reference" "R1R16"
			(at 0 0 90)
			(layer "B.SilkS")
			(hide yes)
			(effects
				(font
					(size 1.27 1.27)
				)
				(justify mirror)
			)
		)
		(property "Value" ""
			(at 0 0 90)
			(layer "B.Fab")
			(effects
				(font
					(size 1.27 1.27)
				)
				(justify mirror)
			)
		)
		(duplicate_pad_numbers_are_jumpers no)
		(fp_poly
			(pts
				(xy 0.2794 -0.1016) (xy -0.2794 -0.1016) (xy -0.2794 0.9906) (xy 0.2794 0.9906)
			)
			(stroke
				(width 0)
				(type default)
			)
			(fill no)
			(layer "B.CrtYd")
		)
		(fp_line
			(start -0.2794 0.9906)
			(end -0.2794 -0.1016)
			(stroke
				(width 0.1)
				(type default)
			)
			(layer "B.Fab")
		)
		(fp_line
			(start 0.2794 0.9906)
			(end -0.2794 0.9906)
			(stroke
				(width 0.1)
				(type default)
			)
			(layer "B.Fab")
		)
		(fp_line
			(start -0.2794 -0.1016)
			(end 0.2794 -0.1016)
			(stroke
				(width 0.1)
				(type default)
			)
			(layer "B.Fab")
		)
		(fp_line
			(start 0.2794 -0.1016)
			(end 0.2794 0.9906)
			(stroke
				(width 0.1)
				(type default)
			)
			(layer "B.Fab")
		)
		(pad "1" smd rect
			(at 0 0 90)
			(size 0.508 0.508)
			(layers "B.Cu" "B.Mask" "B.Paste")
			(net "P3V3_STBY")
		)
		(pad "2" smd rect
			(at 0 0.889 90)
			(size 0.508 0.508)
			(layers "B.Cu" "B.Mask" "B.Paste")
			(net "SMB_PCH_MEZZ_LOM2_SCL")
		)
		(zone
			(layer "B.Cu")
			(hatch none 0.5)
			(connect_pads
				(clearance 0)
			)
			(min_thickness 0.25)
			(keepout
				(tracks not_allowed)
				(vias allowed)
				(pads allowed)
				(copperpour not_allowed)
				(footprints allowed)
			)
			(placement
				(enabled no)
				(sheetname "")
			)
			(fill
				(thermal_gap 0.5)
				(thermal_bridge_width 0.5)
				(island_removal_mode 0)
			)
			(polygon
				(pts
					(xy 469.392 -62.23) (xy 469.392 -62.738) (xy 469.773 -62.738) (xy 469.773 -62.23)
				)
			)
		)
		(zone
			(layer "B.Cu")
			(hatch none 0.5)
			(connect_pads
				(clearance 0)
			)
			(min_thickness 0.25)
			(keepout
				(tracks allowed)
				(vias not_allowed)
				(pads allowed)
				(copperpour not_allowed)
				(footprints allowed)
			)
			(placement
				(enabled no)
				(sheetname "")
			)
			(fill
				(thermal_gap 0.5)
				(thermal_bridge_width 0.5)
				(island_removal_mode 0)
			)
			(polygon
				(pts
					(xy 469.773 -62.23) (xy 469.773 -62.738) (xy 469.392 -62.738) (xy 469.392 -62.23)
				)
			)
		)
	)
	(footprint ""
		(layer "B.Cu")
		(at 419.887146 -48.160432 90)
		(property "Reference" "R1T3"
			(at 0 0 90)
			(layer "B.SilkS")
			(hide yes)
			(effects
				(font
					(size 1.27 1.27)
				)
				(justify mirror)
			)
		)
		(property "Value" ""
			(at 0 0 90)
			(layer "B.Fab")
			(effects
				(font
					(size 1.27 1.27)
				)
				(justify mirror)
			)
		)
		(duplicate_pad_numbers_are_jumpers no)
		(fp_poly
			(pts
				(xy 0.2794 -0.1016) (xy -0.2794 -0.1016) (xy -0.2794 0.9906) (xy 0.2794 0.9906)
			)
			(stroke
				(width 0)
				(type default)
			)
			(fill no)
			(layer "B.CrtYd")
		)
		(fp_line
			(start 0.2794 -0.1016)
			(end 0.2794 0.9906)
			(stroke
				(width 0.1)
				(type default)
			)
			(layer "B.Fab")
		)
		(fp_line
			(start -0.2794 -0.1016)
			(end 0.2794 -0.1016)
			(stroke
				(width 0.1)
				(type default)
			)
			(layer "B.Fab")
		)
		(fp_line
			(start 0.2794 0.9906)
			(end -0.2794 0.9906)
			(stroke
				(width 0.1)
				(type default)
			)
			(layer "B.Fab")
		)
		(fp_line
			(start -0.2794 0.9906)
			(end -0.2794 -0.1016)
			(stroke
				(width 0.1)
				(type default)
			)
			(layer "B.Fab")
		)
		(pad "1" smd rect
			(at 0 0 270)
			(size 0.508 0.508)
			(layers "B.Cu" "B.Mask" "B.Paste")
			(net "P3V3_STBY")
		)
		(pad "2" smd rect
			(at 0 0.889 270)
			(size 0.508 0.508)
			(layers "B.Cu" "B.Mask" "B.Paste")
			(net "SMB_SLOTX24_STBY_LVC3_SDA_R")
		)
		(zone
			(layer "B.Cu")
			(hatch none 0.5)
			(connect_pads
				(clearance 0)
			)
			(min_thickness 0.25)
			(keepout
				(tracks allowed)
				(vias not_allowed)
				(pads allowed)
				(copperpour not_allowed)
				(footprints allowed)
			)
			(placement
				(enabled no)
				(sheetname "")
			)
			(fill
				(thermal_gap 0.5)
				(thermal_bridge_width 0.5)
				(island_removal_mode 0)
			)
			(polygon
				(pts
					(xy 420.141146 -48.414432) (xy 420.141146 -47.906432) (xy 420.522146 -47.906432) (xy 420.522146 -48.414432)
				)
			)
		)
		(zone
			(layer "B.Cu")
			(hatch none 0.5)
			(connect_pads
				(clearance 0)
			)
			(min_thickness 0.25)
			(keepout
				(tracks not_allowed)
				(vias allowed)
				(pads allowed)
				(copperpour not_allowed)
				(footprints allowed)
			)
			(placement
				(enabled no)
				(sheetname "")
			)
			(fill
				(thermal_gap 0.5)
				(thermal_bridge_width 0.5)
				(island_removal_mode 0)
			)
			(polygon
				(pts
					(xy 420.522146 -48.414432) (xy 420.522146 -47.906432) (xy 420.141146 -47.906432) (xy 420.141146 -48.414432)
				)
			)
		)
	)
	(footprint ""
		(layer "B.Cu")
		(at 266.104624 -68.184014 180)
		(property "Reference" "C5P39"
			(at 0 0 0)
			(layer "B.SilkS")
			(hide yes)
			(effects
				(font
					(size 1.27 1.27)
				)
				(justify mirror)
			)
		)
		(property "Value" ""
			(at 0 0 0)
			(layer "B.Fab")
			(effects
				(font
					(size 1.27 1.27)
				)
				(justify mirror)
			)
		)
		(duplicate_pad_numbers_are_jumpers no)
		(fp_poly
			(pts
				(xy 0.7239 -0.2159) (xy -0.7239 -0.2159) (xy -0.7239 1.9939) (xy 0.7239 1.9939)
			)
			(stroke
				(width 0)
				(type default)
			)
			(fill no)
			(layer "B.CrtYd")
		)
		(fp_line
			(start 0.7239 1.9939)
			(end -0.7239 1.9939)
			(stroke
				(width 0.1)
				(type default)
			)
			(layer "B.Fab")
		)
		(fp_line
			(start 0.7239 -0.2159)
			(end 0.7239 1.9939)
			(stroke
				(width 0.1)
				(type default)
			)
			(layer "B.Fab")
		)
		(fp_line
			(start -0.7239 1.9939)
			(end -0.7239 -0.2159)
			(stroke
				(width 0.1)
				(type default)
			)
			(layer "B.Fab")
		)
		(fp_line
			(start -0.7239 -0.2159)
			(end 0.7239 -0.2159)
			(stroke
				(width 0.1)
				(type default)
			)
			(layer "B.Fab")
		)
		(pad "1" smd rect
			(at 0 0)
			(size 1.27 1.016)
			(layers "B.Cu" "B.Mask" "B.Paste")
			(net "PVDDQ_ABC")
		)
		(pad "2" smd rect
			(at 0 1.778)
			(size 1.27 1.016)
			(layers "B.Cu" "B.Mask" "B.Paste")
			(net "GND")
		)
		(zone
			(layer "B.Cu")
			(hatch none 0.5)
			(connect_pads
				(clearance 0)
			)
			(min_thickness 0.25)
			(keepout
				(tracks not_allowed)
				(vias allowed)
				(pads allowed)
				(copperpour not_allowed)
				(footprints allowed)
			)
			(placement
				(enabled no)
				(sheetname "")
			)
			(fill
				(thermal_gap 0.5)
				(thermal_bridge_width 0.5)
				(island_removal_mode 0)
			)
			(polygon
				(pts
					(xy 265.469624 -68.692014) (xy 266.739624 -68.692014) (xy 266.739624 -69.454014) (xy 265.469624 -69.454014)
				)
			)
		)
	)
	(footprint ""
		(layer "B.Cu")
		(at 402.3995 -42.926 -90)
		(property "Reference" "R25W70"
			(at 0.8382 -0.67818 270)
			(unlocked yes)
			(layer "B.SilkS")
			(effects
				(font
					(size 0.4064 0.254)
					(thickness 0.1524)
				)
				(justify left mirror)
			)
		)
		(property "Value" ""
			(at 0 0 90)
			(layer "B.Fab")
			(effects
				(font
					(size 1.27 1.27)
				)
				(justify mirror)
			)
		)
		(duplicate_pad_numbers_are_jumpers no)
		(fp_poly
			(pts
				(xy 0.2794 -0.1016) (xy -0.2794 -0.1016) (xy -0.2794 0.9906) (xy 0.2794 0.9906)
			)
			(stroke
				(width 0)
				(type default)
			)
			(fill no)
			(layer "B.CrtYd")
		)
		(fp_line
			(start -0.2794 0.9906)
			(end -0.2794 -0.1016)
			(stroke
				(width 0.1)
				(type default)
			)
			(layer "B.Fab")
		)
		(fp_line
			(start 0.2794 0.9906)
			(end -0.2794 0.9906)
			(stroke
				(width 0.1)
				(type default)
			)
			(layer "B.Fab")
		)
		(fp_line
			(start -0.2794 -0.1016)
			(end 0.2794 -0.1016)
			(stroke
				(width 0.1)
				(type default)
			)
			(layer "B.Fab")
		)
		(fp_line
			(start 0.2794 -0.1016)
			(end 0.2794 0.9906)
			(stroke
				(width 0.1)
				(type default)
			)
			(layer "B.Fab")
		)
		(pad "1" smd rect
			(at 0 0 90)
			(size 0.508 0.508)
			(layers "B.Cu" "B.Mask" "B.Paste")
			(net "FM_CPU0_FIVR_FAULT_LVT3_R_N")
		)
		(pad "2" smd rect
			(at 0 0.889 90)
			(size 0.508 0.508)
			(layers "B.Cu" "B.Mask" "B.Paste")
			(net "FM_CPU0_FIVR_FAULT_LVT3_N")
		)
		(zone
			(layer "B.Cu")
			(hatch none 0.5)
			(connect_pads
				(clearance 0)
			)
			(min_thickness 0.25)
			(keepout
				(tracks not_allowed)
				(vias allowed)
				(pads allowed)
				(copperpour not_allowed)
				(footprints allowed)
			)
			(placement
				(enabled no)
				(sheetname "")
			)
			(fill
				(thermal_gap 0.5)
				(thermal_bridge_width 0.5)
				(island_removal_mode 0)
			)
			(polygon
				(pts
					(xy 401.7645 -42.672) (xy 401.7645 -43.18) (xy 402.1455 -43.18) (xy 402.1455 -42.672)
				)
			)
		)
		(zone
			(layer "B.Cu")
			(hatch none 0.5)
			(connect_pads
				(clearance 0)
			)
			(min_thickness 0.25)
			(keepout
				(tracks allowed)
				(vias not_allowed)
				(pads allowed)
				(copperpour not_allowed)
				(footprints allowed)
			)
			(placement
				(enabled no)
				(sheetname "")
			)
			(fill
				(thermal_gap 0.5)
				(thermal_bridge_width 0.5)
				(island_removal_mode 0)
			)
			(polygon
				(pts
					(xy 402.1455 -42.672) (xy 402.1455 -43.18) (xy 401.7645 -43.18) (xy 401.7645 -42.672)
				)
			)
		)
	)
	(footprint ""
		(layer "B.Cu")
		(at 485.0892 -128.2065 180)
		(property "Reference" "R1U20"
			(at 0 0 0)
			(layer "B.SilkS")
			(hide yes)
			(effects
				(font
					(size 1.27 1.27)
				)
				(justify mirror)
			)
		)
		(property "Value" ""
			(at 0 0 0)
			(layer "B.Fab")
			(effects
				(font
					(size 1.27 1.27)
				)
				(justify mirror)
			)
		)
		(duplicate_pad_numbers_are_jumpers no)
		(fp_poly
			(pts
				(xy 0.2794 -0.1016) (xy -0.2794 -0.1016) (xy -0.2794 0.9906) (xy 0.2794 0.9906)
			)
			(stroke
				(width 0)
				(type default)
			)
			(fill no)
			(layer "B.CrtYd")
		)
		(fp_line
			(start 0.2794 0.9906)
			(end -0.2794 0.9906)
			(stroke
				(width 0.1)
				(type default)
			)
			(layer "B.Fab")
		)
		(fp_line
			(start 0.2794 -0.1016)
			(end 0.2794 0.9906)
			(stroke
				(width 0.1)
				(type default)
			)
			(layer "B.Fab")
		)
		(fp_line
			(start -0.2794 0.9906)
			(end -0.2794 -0.1016)
			(stroke
				(width 0.1)
				(type default)
			)
			(layer "B.Fab")
		)
		(fp_line
			(start -0.2794 -0.1016)
			(end 0.2794 -0.1016)
			(stroke
				(width 0.1)
				(type default)
			)
			(layer "B.Fab")
		)
		(pad "1" smd rect
			(at 0 0)
			(size 0.508 0.508)
			(layers "B.Cu" "B.Mask" "B.Paste")
			(net "SMB_SMLINK0_STBY_LVC3_SDA")
		)
		(pad "2" smd rect
			(at 0 0.889)
			(size 0.508 0.508)
			(layers "B.Cu" "B.Mask" "B.Paste")
			(net "SMB_SPRINGVILLE_STBY_LVC3_SDA")
		)
		(zone
			(layer "B.Cu")
			(hatch none 0.5)
			(connect_pads
				(clearance 0)
			)
			(min_thickness 0.25)
			(keepout
				(tracks not_allowed)
				(vias allowed)
				(pads allowed)
				(copperpour not_allowed)
				(footprints allowed)
			)
			(placement
				(enabled no)
				(sheetname "")
			)
			(fill
				(thermal_gap 0.5)
				(thermal_bridge_width 0.5)
				(island_removal_mode 0)
			)
			(polygon
				(pts
					(xy 484.8352 -128.8415) (xy 485.3432 -128.8415) (xy 485.3432 -128.4605) (xy 484.8352 -128.4605)
				)
			)
		)
		(zone
			(layer "B.Cu")
			(hatch none 0.5)
			(connect_pads
				(clearance 0)
			)
			(min_thickness 0.25)
			(keepout
				(tracks allowed)
				(vias not_allowed)
				(pads allowed)
				(copperpour not_allowed)
				(footprints allowed)
			)
			(placement
				(enabled no)
				(sheetname "")
			)
			(fill
				(thermal_gap 0.5)
				(thermal_bridge_width 0.5)
				(island_removal_mode 0)
			)
			(polygon
				(pts
					(xy 484.8352 -128.4605) (xy 485.3432 -128.4605) (xy 485.3432 -128.8415) (xy 484.8352 -128.8415)
				)
			)
		)
	)
	(footprint ""
		(layer "B.Cu")
		(at 488.181396 -44.48556 -90)
		(property "Reference" "C1R18"
			(at 0 0 90)
			(layer "B.SilkS")
			(hide yes)
			(effects
				(font
					(size 1.27 1.27)
				)
				(justify mirror)
			)
		)
		(property "Value" ""
			(at 0 0 90)
			(layer "B.Fab")
			(effects
				(font
					(size 1.27 1.27)
				)
				(justify mirror)
			)
		)
		(duplicate_pad_numbers_are_jumpers no)
		(fp_poly
			(pts
				(xy -0.3048 -0.1016) (xy -0.3048 0.9906) (xy 0.3048 0.9906) (xy 0.3048 -0.1016)
			)
			(stroke
				(width 0)
				(type default)
			)
			(fill no)
			(layer "B.CrtYd")
		)
		(fp_line
			(start -0.3048 0.9906)
			(end -0.3048 -0.1016)
			(stroke
				(width 0.1)
				(type default)
			)
			(layer "B.Fab")
		)
		(fp_line
			(start 0.3048 0.9906)
			(end -0.3048 0.9906)
			(stroke
				(width 0.1)
				(type default)
			)
			(layer "B.Fab")
		)
		(fp_line
			(start -0.3048 -0.1016)
			(end 0.3048 -0.1016)
			(stroke
				(width 0.1)
				(type default)
			)
			(layer "B.Fab")
		)
		(fp_line
			(start 0.3048 -0.1016)
			(end 0.3048 0.9906)
			(stroke
				(width 0.1)
				(type default)
			)
			(layer "B.Fab")
		)
		(pad "1" smd rect
			(at 0 0 90)
			(size 0.508 0.508)
			(layers "B.Cu" "B.Mask" "B.Paste")
			(net "P0V9_LAN")
		)
		(pad "2" smd rect
			(at 0 0.889 90)
			(size 0.508 0.508)
			(layers "B.Cu" "B.Mask" "B.Paste")
			(net "GND")
		)
		(zone
			(layer "B.Cu")
			(hatch none 0.5)
			(connect_pads
				(clearance 0)
			)
			(min_thickness 0.25)
			(keepout
				(tracks not_allowed)
				(vias allowed)
				(pads allowed)
				(copperpour not_allowed)
				(footprints allowed)
			)
			(placement
				(enabled no)
				(sheetname "")
			)
			(fill
				(thermal_gap 0.5)
				(thermal_bridge_width 0.5)
				(island_removal_mode 0)
			)
			(polygon
				(pts
					(xy 487.546396 -44.23156) (xy 487.546396 -44.73956) (xy 487.927396 -44.73956) (xy 487.927396 -44.23156)
				)
			)
		)
		(zone
			(layer "B.Cu")
			(hatch none 0.5)
			(connect_pads
				(clearance 0)
			)
			(min_thickness 0.25)
			(keepout
				(tracks allowed)
				(vias not_allowed)
				(pads allowed)
				(copperpour not_allowed)
				(footprints allowed)
			)
			(placement
				(enabled no)
				(sheetname "")
			)
			(fill
				(thermal_gap 0.5)
				(thermal_bridge_width 0.5)
				(island_removal_mode 0)
			)
			(polygon
				(pts
					(xy 487.927396 -44.23156) (xy 487.927396 -44.73956) (xy 487.546396 -44.73956) (xy 487.546396 -44.23156)
				)
			)
		)
	)
	(footprint ""
		(layer "B.Cu")
		(at 449.172838 -155.848812 90)
		(property "Reference" "C25W100"
			(at 0.8382 -0.67818 90)
			(unlocked yes)
			(layer "B.SilkS")
			(effects
				(font
					(size 0.4064 0.254)
					(thickness 0.1524)
				)
				(justify left mirror)
			)
		)
		(property "Value" ""
			(at 0 0 90)
			(layer "B.Fab")
			(effects
				(font
					(size 1.27 1.27)
				)
				(justify mirror)
			)
		)
		(duplicate_pad_numbers_are_jumpers no)
		(fp_poly
			(pts
				(xy -0.3048 -0.1016) (xy -0.3048 0.9906) (xy 0.3048 0.9906) (xy 0.3048 -0.1016)
			)
			(stroke
				(width 0)
				(type default)
			)
			(fill no)
			(layer "B.CrtYd")
		)
		(fp_line
			(start 0.3048 -0.1016)
			(end 0.3048 0.9906)
			(stroke
				(width 0.1)
				(type default)
			)
			(layer "B.Fab")
		)
		(fp_line
			(start -0.3048 -0.1016)
			(end 0.3048 -0.1016)
			(stroke
				(width 0.1)
				(type default)
			)
			(layer "B.Fab")
		)
		(fp_line
			(start 0.3048 0.9906)
			(end -0.3048 0.9906)
			(stroke
				(width 0.1)
				(type default)
			)
			(layer "B.Fab")
		)
		(fp_line
			(start -0.3048 0.9906)
			(end -0.3048 -0.1016)
			(stroke
				(width 0.1)
				(type default)
			)
			(layer "B.Fab")
		)
		(pad "1" smd rect
			(at 0 0 270)
			(size 0.508 0.508)
			(layers "B.Cu" "B.Mask" "B.Paste")
			(net "P3V3_STBY")
		)
		(pad "2" smd rect
			(at 0 0.889 270)
			(size 0.508 0.508)
			(layers "B.Cu" "B.Mask" "B.Paste")
			(net "GND")
		)
		(zone
			(layer "B.Cu")
			(hatch none 0.5)
			(connect_pads
				(clearance 0)
			)
			(min_thickness 0.25)
			(keepout
				(tracks allowed)
				(vias not_allowed)
				(pads allowed)
				(copperpour not_allowed)
				(footprints allowed)
			)
			(placement
				(enabled no)
				(sheetname "")
			)
			(fill
				(thermal_gap 0.5)
				(thermal_bridge_width 0.5)
				(island_removal_mode 0)
			)
			(polygon
				(pts
					(xy 449.426838 -156.102812) (xy 449.426838 -155.594812) (xy 449.807838 -155.594812) (xy 449.807838 -156.102812)
				)
			)
		)
		(zone
			(layer "B.Cu")
			(hatch none 0.5)
			(connect_pads
				(clearance 0)
			)
			(min_thickness 0.25)
			(keepout
				(tracks not_allowed)
				(vias allowed)
				(pads allowed)
				(copperpour not_allowed)
				(footprints allowed)
			)
			(placement
				(enabled no)
				(sheetname "")
			)
			(fill
				(thermal_gap 0.5)
				(thermal_bridge_width 0.5)
				(island_removal_mode 0)
			)
			(polygon
				(pts
					(xy 449.807838 -156.102812) (xy 449.807838 -155.594812) (xy 449.426838 -155.594812) (xy 449.426838 -156.102812)
				)
			)
		)
	)
)
